# T6G (Grand Teton) — schematic netlist excerpt (pin names and nets, part order shuffled) for the footprints in the layout excerpt that follows; sources: Cadence DE-HDL packaged netlist, KiCad conversion of 04192023_DAF0TMB3IC0_F0TG_MB_C_brd_V02_OCP.brd

R1495  Q_RES  33 5% CHIP  pkg 0402LF  page 151 : A = SMB_SCM_2_R1_SCL ; B = SMB_SCM_2_R2_SCL
R1241  Q_RES  1K 1% EMPTY  pkg 0402LF  page 258 : A = P3V3_AUX ; B = ADC128_2_A0

(kicad_pcb
	(version 20260206)
	(generator "pcbnew")
	(generator_version "10.0")
	(general
		(thickness 1.6)
		(legacy_teardrops no)
	)
	(paper "A4")
	(title_block
		(title "04192023_DAF0TMB3IC0_F0TG_MB_C_brd_V02_OCP.brd")
		(comment 1 "Grand Teton / footprints 8200-8201 of 8354")
	)
	(layers
		(0 "F.Cu" signal "TOP")
		(4 "In1.Cu" signal "GND")
		(6 "In2.Cu" signal "IN1")
		(8 "In3.Cu" signal "GND1")
		(10 "In4.Cu" signal "IN2")
		(12 "In5.Cu" signal "GND2")
		(14 "In6.Cu" signal "IN3")
		(16 "In7.Cu" signal "GND3")
		(18 "In8.Cu" signal "VCC")
		(20 "In9.Cu" signal "VCC1")
		(22 "In10.Cu" signal "GND4")
		(24 "In11.Cu" signal "IN4")
		(26 "In12.Cu" signal "GND5")
		(28 "In13.Cu" signal "IN5")
		(30 "In14.Cu" signal "GND6")
		(32 "In15.Cu" signal "IN6")
		(34 "In16.Cu" signal "GND7")
		(2 "B.Cu" signal "BOTTOM")
		(9 "F.Adhes" user "F.Adhesive")
		(11 "B.Adhes" user "B.Adhesive")
		(13 "F.Paste" user "Package Geometry/Pastemask Top")
		(15 "B.Paste" user "Package Geometry/Pastemask Bottom")
		(5 "F.SilkS" user "Ref Des/Silkscreen Top")
		(7 "B.SilkS" user "Ref Des/Silkscreen Bottom")
		(1 "F.Mask" user "Board Geometry/Soldermask Top")
		(3 "B.Mask" user "Board Geometry/Soldermask Bottom")
		(17 "Dwgs.User" user "User.Drawings")
		(19 "Cmts.User" user "User.Comments")
		(21 "Eco1.User" user "User.Eco1")
		(23 "Eco2.User" user "User.Eco2")
		(25 "Edge.Cuts" user "Board Geometry/Outline")
		(27 "Margin" user)
		(31 "F.CrtYd" user "Package Geometry/Place Bound Top")
		(29 "B.CrtYd" user "Package Geometry/Place Bound Bottom")
		(35 "F.Fab" user "Ref Des/Assembly Top")
		(33 "B.Fab" user "Ref Des/Assembly Bottom")
	)
	(footprint ""
		(layer "B.Cu")
		(at 216.142824 -328.032872 180)
		(property "Reference" "R1241"
			(at 0 0 0)
			(layer "B.SilkS")
			(hide yes)
			(effects
				(font
					(size 1.27 1.27)
				)
				(justify mirror)
			)
		)
		(property "Value" ""
			(at 0 0 0)
			(layer "B.Fab")
			(effects
				(font
					(size 1.27 1.27)
				)
				(justify mirror)
			)
		)
		(duplicate_pad_numbers_are_jumpers no)
		(fp_line
			(start 0.7874 0.4064)
			(end 0.7874 -0.4064)
			(stroke
				(width 0.1524)
				(type default)
			)
			(layer "B.SilkS")
		)
		(fp_line
			(start 0.7874 -0.4064)
			(end -0.7874 -0.4064)
			(stroke
				(width 0.1524)
				(type default)
			)
			(layer "B.SilkS")
		)
		(fp_line
			(start -0.7874 0.4064)
			(end 0.7874 0.4064)
			(stroke
				(width 0.1524)
				(type default)
			)
			(layer "B.SilkS")
		)
		(fp_line
			(start -0.7874 -0.4064)
			(end -0.7874 0.4064)
			(stroke
				(width 0.1524)
				(type default)
			)
			(layer "B.SilkS")
		)
		(fp_line
			(start 0.67945 0.3048)
			(end 0.67945 -0.305054)
			(stroke
				(width 0.1)
				(type default)
			)
			(layer "B.Fab")
		)
		(fp_line
			(start 0.67945 -0.305054)
			(end 0.12065 -0.305054)
			(stroke
				(width 0.1)
				(type default)
			)
			(layer "B.Fab")
		)
		(fp_line
			(start 0.12065 0.3048)
			(end 0.67945 0.3048)
			(stroke
				(width 0.1)
				(type default)
			)
			(layer "B.Fab")
		)
		(fp_line
			(start 0.12065 0.2794)
			(end 0.12065 0.3048)
			(stroke
				(width 0.1)
				(type default)
			)
			(layer "B.Fab")
		)
		(fp_line
			(start 0.12065 -0.2794)
			(end -0.12065 -0.2794)
			(stroke
				(width 0.1)
				(type default)
			)
			(layer "B.Fab")
		)
		(fp_line
			(start 0.12065 -0.305054)
			(end 0.12065 -0.2794)
			(stroke
				(width 0.1)
				(type default)
			)
			(layer "B.Fab")
		)
		(fp_line
			(start -0.120396 0.3048)
			(end -0.120396 0.2794)
			(stroke
				(width 0.1)
				(type default)
			)
			(layer "B.Fab")
		)
		(fp_line
			(start -0.120396 0.2794)
			(end 0.12065 0.2794)
			(stroke
				(width 0.1)
				(type default)
			)
			(layer "B.Fab")
		)
		(fp_line
			(start -0.12065 -0.2794)
			(end -0.12065 -0.3048)
			(stroke
				(width 0.1)
				(type default)
			)
			(layer "B.Fab")
		)
		(fp_line
			(start -0.12065 -0.3048)
			(end -0.67945 -0.3048)
			(stroke
				(width 0.1)
				(type default)
			)
			(layer "B.Fab")
		)
		(fp_line
			(start -0.67945 0.3048)
			(end -0.120396 0.3048)
			(stroke
				(width 0.1)
				(type default)
			)
			(layer "B.Fab")
		)
		(fp_line
			(start -0.67945 -0.3048)
			(end -0.67945 0.3048)
			(stroke
				(width 0.1)
				(type default)
			)
			(layer "B.Fab")
		)
		(pad "1" smd circle
			(at 0.40005 0)
			(size 0 0)
			(layers "B.Cu" "B.Mask" "B.Paste")
			(net "P3V3_AUX")
		)
		(pad "2" smd circle
			(at -0.40005 0)
			(size 0 0)
			(layers "B.Cu" "B.Mask" "B.Paste")
			(net "ADC128_2_A0")
		)
	)
	(footprint ""
		(layer "B.Cu")
		(at 20.32 -366.903)
		(property "Reference" "R1495"
			(at 0 0 0)
			(layer "B.SilkS")
			(hide yes)
			(effects
				(font
					(size 1.27 1.27)
				)
				(justify mirror)
			)
		)
		(property "Value" ""
			(at 0 0 0)
			(layer "B.Fab")
			(effects
				(font
					(size 1.27 1.27)
				)
				(justify mirror)
			)
		)
		(duplicate_pad_numbers_are_jumpers no)
		(fp_line
			(start -0.7874 -0.4064)
			(end -0.7874 0.4064)
			(stroke
				(width 0.1524)
				(type default)
			)
			(layer "B.SilkS")
		)
		(fp_line
			(start -0.7874 0.4064)
			(end 0.7874 0.4064)
			(stroke
				(width 0.1524)
				(type default)
			)
			(layer "B.SilkS")
		)
		(fp_line
			(start 0.7874 -0.4064)
			(end -0.7874 -0.4064)
			(stroke
				(width 0.1524)
				(type default)
			)
			(layer "B.SilkS")
		)
		(fp_line
			(start 0.7874 0.4064)
			(end 0.7874 -0.4064)
			(stroke
				(width 0.1524)
				(type default)
			)
			(layer "B.SilkS")
		)
		(fp_line
			(start -0.67945 -0.3048)
			(end -0.67945 0.3048)
			(stroke
				(width 0.1)
				(type default)
			)
			(layer "B.Fab")
		)
		(fp_line
			(start -0.67945 0.3048)
			(end -0.120396 0.3048)
			(stroke
				(width 0.1)
				(type default)
			)
			(layer "B.Fab")
		)
		(fp_line
			(start -0.12065 -0.3048)
			(end -0.67945 -0.3048)
			(stroke
				(width 0.1)
				(type default)
			)
			(layer "B.Fab")
		)
		(fp_line
			(start -0.12065 -0.2794)
			(end -0.12065 -0.3048)
			(stroke
				(width 0.1)
				(type default)
			)
			(layer "B.Fab")
		)
		(fp_line
			(start -0.120396 0.2794)
			(end 0.12065 0.2794)
			(stroke
				(width 0.1)
				(type default)
			)
			(layer "B.Fab")
		)
		(fp_line
			(start -0.120396 0.3048)
			(end -0.120396 0.2794)
			(stroke
				(width 0.1)
				(type default)
			)
			(layer "B.Fab")
		)
		(fp_line
			(start 0.12065 -0.305054)
			(end 0.12065 -0.2794)
			(stroke
				(width 0.1)
				(type default)
			)
			(layer "B.Fab")
		)
		(fp_line
			(start 0.12065 -0.2794)
			(end -0.12065 -0.2794)
			(stroke
				(width 0.1)
				(type default)
			)
			(layer "B.Fab")
		)
		(fp_line
			(start 0.12065 0.2794)
			(end 0.12065 0.3048)
			(stroke
				(width 0.1)
				(type default)
			)
			(layer "B.Fab")
		)
		(fp_line
			(start 0.12065 0.3048)
			(end 0.67945 0.3048)
			(stroke
				(width 0.1)
				(type default)
			)
			(layer "B.Fab")
		)
		(fp_line
			(start 0.67945 -0.305054)
			(end 0.12065 -0.305054)
			(stroke
				(width 0.1)
				(type default)
			)
			(layer "B.Fab")
		)
		(fp_line
			(start 0.67945 0.3048)
			(end 0.67945 -0.305054)
			(stroke
				(width 0.1)
				(type default)
			)
			(layer "B.Fab")
		)
		(pad "1" smd circle
			(at 0.40005 0 180)
			(size 0 0)
			(layers "B.Cu" "B.Mask" "B.Paste")
			(net "SMB_SCM_2_R1_SCL")
		)
		(pad "2" smd circle
			(at -0.40005 0 180)
			(size 0 0)
			(layers "B.Cu" "B.Mask" "B.Paste")
			(net "SMB_SCM_2_R2_SCL")
		)
	)
)
